(kicad_pcb
	(version 20260206)
	(generator "pcbnew")
	(generator_version "10.0")
	(general
		(thickness 1.6)
		(legacy_teardrops no)
	)
	(paper "A4")
	(title_block
		(title "12092022_DA0F0TMDCD0_F0T_Management_Board_D_brd_V3_OCP.brd")
		(comment 1 "Grand Teton / footprints 180-185 of 1440")
	)
	(layers
		(0 "F.Cu" signal "TOP")
		(4 "In1.Cu" signal "GND")
		(6 "In2.Cu" signal "IN1")
		(8 "In3.Cu" signal "GND1")
		(10 "In4.Cu" signal "IN2")
		(12 "In5.Cu" signal "VCC")
		(14 "In6.Cu" signal "VCC1")
		(16 "In7.Cu" signal "IN3")
		(18 "In8.Cu" signal "GND2")
		(20 "In9.Cu" signal "IN4")
		(22 "In10.Cu" signal "GND3")
		(2 "B.Cu" signal "BOTTOM")
		(9 "F.Adhes" user "F.Adhesive")
		(11 "B.Adhes" user "B.Adhesive")
		(13 "F.Paste" user "Package Geometry/Pastemask Top")
		(15 "B.Paste" user "Package Geometry/Pastemask Bottom")
		(5 "F.SilkS" user "Ref Des/Silkscreen Top")
		(7 "B.SilkS" user "Ref Des/Silkscreen Bottom")
		(1 "F.Mask" user "Board Geometry/Soldermask Top")
		(3 "B.Mask" user "Board Geometry/Soldermask Bottom")
		(17 "Dwgs.User" user "User.Drawings")
		(19 "Cmts.User" user "User.Comments")
		(21 "Eco1.User" user "User.Eco1")
		(23 "Eco2.User" user "User.Eco2")
		(25 "Edge.Cuts" user "Board Geometry/Outline")
		(27 "Margin" user)
		(31 "F.CrtYd" user "Package Geometry/Place Bound Top")
		(29 "B.CrtYd" user "Package Geometry/Place Bound Bottom")
		(35 "F.Fab" user "Ref Des/Assembly Top")
		(33 "B.Fab" user "Ref Des/Assembly Bottom")
	)
	(footprint ""
		(layer "F.Cu")
		(at 75.032108 -11.061954 90)
		(property "Reference" "D10"
			(at -1.029716 1.187704 90)
			(unlocked yes)
			(layer "F.SilkS")
			(effects
				(font
					(size 0.7874 0.5842)
					(thickness 0.1524)
				)
				(justify left)
			)
		)
		(property "Value" ""
			(at 0 0 90)
			(layer "F.Fab")
			(effects
				(font
					(size 1.27 1.27)
				)
			)
		)
		(duplicate_pad_numbers_are_jumpers no)
		(fp_line
			(start 0.94488 -0.450088)
			(end -0.854964 -0.450088)
			(stroke
				(width 0.1524)
				(type default)
			)
			(layer "F.SilkS")
		)
		(fp_line
			(start -0.854964 -0.450088)
			(end -0.854964 0.450088)
			(stroke
				(width 0.1524)
				(type default)
			)
			(layer "F.SilkS")
		)
		(fp_line
			(start 0.870458 -0.2794)
			(end 0.845058 0.4064)
			(stroke
				(width 0.1524)
				(type default)
			)
			(layer "F.SilkS")
		)
		(fp_line
			(start 0.845058 0.4064)
			(end 0.845058 -0.381)
			(stroke
				(width 0.1524)
				(type default)
			)
			(layer "F.SilkS")
		)
		(fp_line
			(start 0.94488 0.450088)
			(end 0.94488 -0.450088)
			(stroke
				(width 0.1524)
				(type default)
			)
			(layer "F.SilkS")
		)
		(fp_line
			(start -0.854964 0.450088)
			(end 0.925068 0.450088)
			(stroke
				(width 0.1524)
				(type default)
			)
			(layer "F.SilkS")
		)
		(fp_line
			(start 0.54991 -0.350012)
			(end -0.54991 -0.350012)
			(stroke
				(width 0.1)
				(type default)
			)
			(layer "F.Fab")
		)
		(fp_line
			(start -0.54991 -0.350012)
			(end -0.54991 0.350012)
			(stroke
				(width 0.1)
				(type default)
			)
			(layer "F.Fab")
		)
		(fp_line
			(start 0.54991 0.350012)
			(end 0.54991 -0.350012)
			(stroke
				(width 0.1)
				(type default)
			)
			(layer "F.Fab")
		)
		(fp_line
			(start -0.54991 0.350012)
			(end 0.54991 0.350012)
			(stroke
				(width 0.1)
				(type default)
			)
			(layer "F.Fab")
		)
		(fp_text user "+"
			(at -0.808228 0.239014 270)
			(unlocked yes)
			(layer "F.SilkS")
			(effects
				(font
					(size 1.905 1.4224)
					(thickness 0.1524)
				)
				(justify left)
			)
		)
		(fp_text user "-"
			(at 2.196846 0.577342 270)
			(unlocked yes)
			(layer "F.SilkS")
			(effects
				(font
					(size 1.905 1.4224)
					(thickness 0.1524)
				)
				(justify left)
			)
		)
		(fp_text user "-"
			(at 2.48539 0.239014 270)
			(unlocked yes)
			(layer "F.Fab")
			(effects
				(font
					(size 1.905 1.4224)
					(thickness 0.1524)
				)
				(justify left)
			)
		)
		(fp_text user "+"
			(at -0.808228 0.239014 270)
			(unlocked yes)
			(layer "F.Fab")
			(effects
				(font
					(size 1.905 1.4224)
					(thickness 0.1524)
				)
				(justify left)
			)
		)
		(pad "A" smd rect
			(at -0.424942 0 90)
			(size 0.5588 0.6096)
			(layers "F.Cu" "F.Mask" "F.Paste")
			(net "REAR_AC_PWR_BTN")
		)
		(pad "C" smd rect
			(at 0.424942 0 270)
			(size 0.5588 0.6096)
			(layers "F.Cu" "F.Mask" "F.Paste")
			(net "GND")
		)
	)
	(footprint ""
		(layer "F.Cu")
		(at 39.37 -73.914 90)
		(property "Reference" "C26"
			(at 0 0 90)
			(layer "F.SilkS")
			(hide yes)
			(effects
				(font
					(size 1.27 1.27)
				)
			)
		)
		(property "Value" ""
			(at 0 0 90)
			(layer "F.Fab")
			(effects
				(font
					(size 1.27 1.27)
				)
			)
		)
		(duplicate_pad_numbers_are_jumpers no)
		(fp_line
			(start 0.7874 -0.4064)
			(end 0.7874 0.141986)
			(stroke
				(width 0.1524)
				(type default)
			)
			(layer "F.SilkS")
		)
		(fp_line
			(start -0.7874 -0.4064)
			(end 0.7874 -0.4064)
			(stroke
				(width 0.1524)
				(type default)
			)
			(layer "F.SilkS")
		)
		(fp_line
			(start -0.7874 0.070866)
			(end -0.7874 -0.4064)
			(stroke
				(width 0.1524)
				(type default)
			)
			(layer "F.SilkS")
		)
		(fp_line
			(start 0.413004 0.4064)
			(end -0.440436 0.4064)
			(stroke
				(width 0.1524)
				(type default)
			)
			(layer "F.SilkS")
		)
		(fp_line
			(start -0.12065 -0.305054)
			(end -0.12065 -0.2794)
			(stroke
				(width 0.1)
				(type default)
			)
			(layer "F.Fab")
		)
		(fp_line
			(start -0.67945 -0.305054)
			(end -0.12065 -0.305054)
			(stroke
				(width 0.1)
				(type default)
			)
			(layer "F.Fab")
		)
		(fp_line
			(start 0.67945 -0.3048)
			(end 0.67945 0.3048)
			(stroke
				(width 0.1)
				(type default)
			)
			(layer "F.Fab")
		)
		(fp_line
			(start 0.12065 -0.3048)
			(end 0.67945 -0.3048)
			(stroke
				(width 0.1)
				(type default)
			)
			(layer "F.Fab")
		)
		(fp_line
			(start 0.12065 -0.2794)
			(end 0.12065 -0.3048)
			(stroke
				(width 0.1)
				(type default)
			)
			(layer "F.Fab")
		)
		(fp_line
			(start -0.12065 -0.2794)
			(end 0.12065 -0.2794)
			(stroke
				(width 0.1)
				(type default)
			)
			(layer "F.Fab")
		)
		(fp_line
			(start 0.120396 0.2794)
			(end -0.12065 0.2794)
			(stroke
				(width 0.1)
				(type default)
			)
			(layer "F.Fab")
		)
		(fp_line
			(start -0.12065 0.2794)
			(end -0.12065 0.3048)
			(stroke
				(width 0.1)
				(type default)
			)
			(layer "F.Fab")
		)
		(fp_line
			(start 0.67945 0.3048)
			(end 0.120396 0.3048)
			(stroke
				(width 0.1)
				(type default)
			)
			(layer "F.Fab")
		)
		(fp_line
			(start 0.120396 0.3048)
			(end 0.120396 0.2794)
			(stroke
				(width 0.1)
				(type default)
			)
			(layer "F.Fab")
		)
		(fp_line
			(start -0.12065 0.3048)
			(end -0.67945 0.3048)
			(stroke
				(width 0.1)
				(type default)
			)
			(layer "F.Fab")
		)
		(fp_line
			(start -0.67945 0.3048)
			(end -0.67945 -0.305054)
			(stroke
				(width 0.1)
				(type default)
			)
			(layer "F.Fab")
		)
		(pad "1" smd circle
			(at -0.40005 0 90)
			(size 0 0)
			(layers "F.Cu" "F.Mask" "F.Paste")
			(net "P3V3_AUX")
		)
		(pad "2" smd circle
			(at 0.40005 0 90)
			(size 0 0)
			(layers "F.Cu" "F.Mask" "F.Paste")
			(net "GND")
		)
	)
	(footprint ""
		(layer "F.Cu")
		(at 74.01052 -27.738832 90)
		(property "Reference" "D3"
			(at -1.830832 8.94715 90)
			(unlocked yes)
			(layer "F.SilkS")
			(effects
				(font
					(size 0.7874 0.5842)
					(thickness 0.1524)
				)
				(justify left)
			)
		)
		(property "Value" ""
			(at 0 0 90)
			(layer "F.Fab")
			(effects
				(font
					(size 1.27 1.27)
				)
			)
		)
		(duplicate_pad_numbers_are_jumpers no)
		(fp_line
			(start 1.778 -0.5588)
			(end 1.3208 -0.5588)
			(stroke
				(width 0.1524)
				(type default)
			)
			(layer "F.SilkS")
		)
		(fp_line
			(start 1.778 -0.5588)
			(end 1.778 0.5588)
			(stroke
				(width 0.1524)
				(type default)
			)
			(layer "F.SilkS")
		)
		(fp_line
			(start 1.4732 -0.5588)
			(end 1.4732 0.5588)
			(stroke
				(width 0.1524)
				(type default)
			)
			(layer "F.SilkS")
		)
		(fp_line
			(start 1.3208 -0.5588)
			(end 1.3208 0.5588)
			(stroke
				(width 0.1524)
				(type default)
			)
			(layer "F.SilkS")
		)
		(fp_line
			(start -1.3208 -0.5588)
			(end 1.3208 -0.5588)
			(stroke
				(width 0.1524)
				(type default)
			)
			(layer "F.SilkS")
		)
		(fp_line
			(start 1.778 0.5588)
			(end 1.3208 0.5588)
			(stroke
				(width 0.1524)
				(type default)
			)
			(layer "F.SilkS")
		)
		(fp_line
			(start 1.6256 0.5588)
			(end 1.6256 -0.5588)
			(stroke
				(width 0.1524)
				(type default)
			)
			(layer "F.SilkS")
		)
		(fp_line
			(start 1.3208 0.5588)
			(end -1.3208 0.5588)
			(stroke
				(width 0.1524)
				(type default)
			)
			(layer "F.SilkS")
		)
		(fp_line
			(start -1.3208 0.5588)
			(end -1.3208 -0.5588)
			(stroke
				(width 0.1524)
				(type default)
			)
			(layer "F.SilkS")
		)
		(fp_line
			(start 1.236726 -0.508)
			(end 1.1684 -0.508)
			(stroke
				(width 0.1)
				(type default)
			)
			(layer "F.Fab")
		)
		(fp_line
			(start 1.1684 -0.508)
			(end -1.1684 -0.508)
			(stroke
				(width 0.1)
				(type default)
			)
			(layer "F.Fab")
		)
		(fp_line
			(start -1.1684 -0.508)
			(end -1.235964 -0.508)
			(stroke
				(width 0.1)
				(type default)
			)
			(layer "F.Fab")
		)
		(fp_line
			(start -1.235964 -0.508)
			(end -1.235964 0.508)
			(stroke
				(width 0.1)
				(type default)
			)
			(layer "F.Fab")
		)
		(fp_line
			(start 1.236726 0.508)
			(end 1.236726 -0.508)
			(stroke
				(width 0.1)
				(type default)
			)
			(layer "F.Fab")
		)
		(fp_line
			(start 1.1684 0.508)
			(end 1.236726 0.508)
			(stroke
				(width 0.1)
				(type default)
			)
			(layer "F.Fab")
		)
		(fp_line
			(start -1.1684 0.508)
			(end 1.1684 0.508)
			(stroke
				(width 0.1)
				(type default)
			)
			(layer "F.Fab")
		)
		(fp_line
			(start -1.235964 0.508)
			(end -1.1684 0.508)
			(stroke
				(width 0.1)
				(type default)
			)
			(layer "F.Fab")
		)
		(fp_text user "+"
			(at -1.526032 -1.43637 90)
			(unlocked yes)
			(layer "F.SilkS")
			(effects
				(font
					(size 1.905 1.4224)
					(thickness 0.1524)
				)
				(justify left)
			)
		)
		(fp_text user "-"
			(at 0.328168 -1.10617 90)
			(unlocked yes)
			(layer "F.SilkS")
			(effects
				(font
					(size 1.905 1.4224)
					(thickness 0.1524)
				)
				(justify left)
			)
		)
		(fp_text user "-"
			(at 1.524 -0.24765 90)
			(unlocked yes)
			(layer "F.Fab")
			(effects
				(font
					(size 1.905 1.4224)
					(thickness 0.1524)
				)
				(justify left)
			)
		)
		(fp_text user "+"
			(at -2.5654 -0.24765 90)
			(unlocked yes)
			(layer "F.Fab")
			(effects
				(font
					(size 1.905 1.4224)
					(thickness 0.1524)
				)
				(justify left)
			)
		)
		(pad "A" smd rect
			(at -0.750062 0 90)
			(size 0.8128 0.8128)
			(layers "F.Cu" "F.Mask" "F.Paste")
			(net "LED_POSTCODE_3_R")
		)
		(pad "C" smd rect
			(at 0.750062 0 90)
			(size 0.8128 0.8128)
			(layers "F.Cu" "F.Mask" "F.Paste")
			(net "GND")
		)
	)
	(footprint ""
		(layer "F.Cu")
		(at 39.8272 -78.6638 180)
		(property "Reference" "R558"
			(at 0 0 180)
			(layer "F.SilkS")
			(hide yes)
			(effects
				(font
					(size 1.27 1.27)
				)
			)
		)
		(property "Value" ""
			(at 0 0 180)
			(layer "F.Fab")
			(effects
				(font
					(size 1.27 1.27)
				)
			)
		)
		(duplicate_pad_numbers_are_jumpers no)
		(fp_line
			(start 0.7874 0.4064)
			(end -0.7874 0.4064)
			(stroke
				(width 0.1524)
				(type default)
			)
			(layer "F.SilkS")
		)
		(fp_line
			(start 0.7874 -0.4064)
			(end 0.7874 0.4064)
			(stroke
				(width 0.1524)
				(type default)
			)
			(layer "F.SilkS")
		)
		(fp_line
			(start -0.7874 0.4064)
			(end -0.7874 -0.4064)
			(stroke
				(width 0.1524)
				(type default)
			)
			(layer "F.SilkS")
		)
		(fp_line
			(start -0.7874 -0.4064)
			(end 0.7874 -0.4064)
			(stroke
				(width 0.1524)
				(type default)
			)
			(layer "F.SilkS")
		)
		(fp_line
			(start 0.67945 0.3048)
			(end 0.120396 0.3048)
			(stroke
				(width 0.1)
				(type default)
			)
			(layer "F.Fab")
		)
		(fp_line
			(start 0.67945 -0.3048)
			(end 0.67945 0.3048)
			(stroke
				(width 0.1)
				(type default)
			)
			(layer "F.Fab")
		)
		(fp_line
			(start 0.12065 -0.2794)
			(end 0.12065 -0.3048)
			(stroke
				(width 0.1)
				(type default)
			)
			(layer "F.Fab")
		)
		(fp_line
			(start 0.12065 -0.3048)
			(end 0.67945 -0.3048)
			(stroke
				(width 0.1)
				(type default)
			)
			(layer "F.Fab")
		)
		(fp_line
			(start 0.120396 0.3048)
			(end 0.120396 0.2794)
			(stroke
				(width 0.1)
				(type default)
			)
			(layer "F.Fab")
		)
		(fp_line
			(start 0.120396 0.2794)
			(end -0.12065 0.2794)
			(stroke
				(width 0.1)
				(type default)
			)
			(layer "F.Fab")
		)
		(fp_line
			(start -0.12065 0.3048)
			(end -0.67945 0.3048)
			(stroke
				(width 0.1)
				(type default)
			)
			(layer "F.Fab")
		)
		(fp_line
			(start -0.12065 0.2794)
			(end -0.12065 0.3048)
			(stroke
				(width 0.1)
				(type default)
			)
			(layer "F.Fab")
		)
		(fp_line
			(start -0.12065 -0.2794)
			(end 0.12065 -0.2794)
			(stroke
				(width 0.1)
				(type default)
			)
			(layer "F.Fab")
		)
		(fp_line
			(start -0.12065 -0.305054)
			(end -0.12065 -0.2794)
			(stroke
				(width 0.1)
				(type default)
			)
			(layer "F.Fab")
		)
		(fp_line
			(start -0.67945 0.3048)
			(end -0.67945 -0.305054)
			(stroke
				(width 0.1)
				(type default)
			)
			(layer "F.Fab")
		)
		(fp_line
			(start -0.67945 -0.305054)
			(end -0.12065 -0.305054)
			(stroke
				(width 0.1)
				(type default)
			)
			(layer "F.Fab")
		)
		(pad "1" smd circle
			(at -0.40005 0 180)
			(size 0 0)
			(layers "F.Cu" "F.Mask" "F.Paste")
			(net "P3V3_AUX")
		)
		(pad "2" smd circle
			(at 0.40005 0 180)
			(size 0 0)
			(layers "F.Cu" "F.Mask" "F.Paste")
			(net "SPI_BMC_CS1_FLASH_R_N")
		)
	)
	(footprint ""
		(layer "F.Cu")
		(at 85.29955 -40.617394 180)
		(property "Reference" "R327"
			(at 0 0 180)
			(layer "F.SilkS")
			(hide yes)
			(effects
				(font
					(size 1.27 1.27)
				)
			)
		)
		(property "Value" ""
			(at 0 0 180)
			(layer "F.Fab")
			(effects
				(font
					(size 1.27 1.27)
				)
			)
		)
		(duplicate_pad_numbers_are_jumpers no)
		(fp_line
			(start 0.7874 0.4064)
			(end -0.7874 0.4064)
			(stroke
				(width 0.1524)
				(type default)
			)
			(layer "F.SilkS")
		)
		(fp_line
			(start 0.7874 -0.4064)
			(end 0.7874 0.4064)
			(stroke
				(width 0.1524)
				(type default)
			)
			(layer "F.SilkS")
		)
		(fp_line
			(start -0.7874 0.4064)
			(end -0.7874 -0.4064)
			(stroke
				(width 0.1524)
				(type default)
			)
			(layer "F.SilkS")
		)
		(fp_line
			(start -0.7874 -0.4064)
			(end 0.7874 -0.4064)
			(stroke
				(width 0.1524)
				(type default)
			)
			(layer "F.SilkS")
		)
		(fp_line
			(start 0.67945 0.3048)
			(end 0.120396 0.3048)
			(stroke
				(width 0.1)
				(type default)
			)
			(layer "F.Fab")
		)
		(fp_line
			(start 0.67945 -0.3048)
			(end 0.67945 0.3048)
			(stroke
				(width 0.1)
				(type default)
			)
			(layer "F.Fab")
		)
		(fp_line
			(start 0.12065 -0.2794)
			(end 0.12065 -0.3048)
			(stroke
				(width 0.1)
				(type default)
			)
			(layer "F.Fab")
		)
		(fp_line
			(start 0.12065 -0.3048)
			(end 0.67945 -0.3048)
			(stroke
				(width 0.1)
				(type default)
			)
			(layer "F.Fab")
		)
		(fp_line
			(start 0.120396 0.3048)
			(end 0.120396 0.2794)
			(stroke
				(width 0.1)
				(type default)
			)
			(layer "F.Fab")
		)
		(fp_line
			(start 0.120396 0.2794)
			(end -0.12065 0.2794)
			(stroke
				(width 0.1)
				(type default)
			)
			(layer "F.Fab")
		)
		(fp_line
			(start -0.12065 0.3048)
			(end -0.67945 0.3048)
			(stroke
				(width 0.1)
				(type default)
			)
			(layer "F.Fab")
		)
		(fp_line
			(start -0.12065 0.2794)
			(end -0.12065 0.3048)
			(stroke
				(width 0.1)
				(type default)
			)
			(layer "F.Fab")
		)
		(fp_line
			(start -0.12065 -0.2794)
			(end 0.12065 -0.2794)
			(stroke
				(width 0.1)
				(type default)
			)
			(layer "F.Fab")
		)
		(fp_line
			(start -0.12065 -0.305054)
			(end -0.12065 -0.2794)
			(stroke
				(width 0.1)
				(type default)
			)
			(layer "F.Fab")
		)
		(fp_line
			(start -0.67945 0.3048)
			(end -0.67945 -0.305054)
			(stroke
				(width 0.1)
				(type default)
			)
			(layer "F.Fab")
		)
		(fp_line
			(start -0.67945 -0.305054)
			(end -0.12065 -0.305054)
			(stroke
				(width 0.1)
				(type default)
			)
			(layer "F.Fab")
		)
		(pad "1" smd circle
			(at -0.40005 0 180)
			(size 0 0)
			(layers "F.Cu" "F.Mask" "F.Paste")
			(net "GND")
		)
		(pad "2" smd circle
			(at 0.40005 0 180)
			(size 0 0)
			(layers "F.Cu" "F.Mask" "F.Paste")
			(net "M_BMC_DDR4_MA<1>")
		)
	)
	(footprint ""
		(layer "F.Cu")
		(at 40.513 -89.027 180)
		(property "Reference" "R496"
			(at 0 0 180)
			(layer "F.SilkS")
			(hide yes)
			(effects
				(font
					(size 1.27 1.27)
				)
			)
		)
		(property "Value" ""
			(at 0 0 180)
			(layer "F.Fab")
			(effects
				(font
					(size 1.27 1.27)
				)
			)
		)
		(duplicate_pad_numbers_are_jumpers no)
		(fp_line
			(start 0.7874 0.4064)
			(end -0.7874 0.4064)
			(stroke
				(width 0.1524)
				(type default)
			)
			(layer "F.SilkS")
		)
		(fp_line
			(start 0.7874 -0.4064)
			(end 0.7874 0.4064)
			(stroke
				(width 0.1524)
				(type default)
			)
			(layer "F.SilkS")
		)
		(fp_line
			(start -0.7874 0.4064)
			(end -0.7874 -0.4064)
			(stroke
				(width 0.1524)
				(type default)
			)
			(layer "F.SilkS")
		)
		(fp_line
			(start -0.7874 -0.4064)
			(end 0.7874 -0.4064)
			(stroke
				(width 0.1524)
				(type default)
			)
			(layer "F.SilkS")
		)
		(fp_line
			(start 0.67945 0.3048)
			(end 0.120396 0.3048)
			(stroke
				(width 0.1)
				(type default)
			)
			(layer "F.Fab")
		)
		(fp_line
			(start 0.67945 -0.3048)
			(end 0.67945 0.3048)
			(stroke
				(width 0.1)
				(type default)
			)
			(layer "F.Fab")
		)
		(fp_line
			(start 0.12065 -0.2794)
			(end 0.12065 -0.3048)
			(stroke
				(width 0.1)
				(type default)
			)
			(layer "F.Fab")
		)
		(fp_line
			(start 0.12065 -0.3048)
			(end 0.67945 -0.3048)
			(stroke
				(width 0.1)
				(type default)
			)
			(layer "F.Fab")
		)
		(fp_line
			(start 0.120396 0.3048)
			(end 0.120396 0.2794)
			(stroke
				(width 0.1)
				(type default)
			)
			(layer "F.Fab")
		)
		(fp_line
			(start 0.120396 0.2794)
			(end -0.12065 0.2794)
			(stroke
				(width 0.1)
				(type default)
			)
			(layer "F.Fab")
		)
		(fp_line
			(start -0.12065 0.3048)
			(end -0.67945 0.3048)
			(stroke
				(width 0.1)
				(type default)
			)
			(layer "F.Fab")
		)
		(fp_line
			(start -0.12065 0.2794)
			(end -0.12065 0.3048)
			(stroke
				(width 0.1)
				(type default)
			)
			(layer "F.Fab")
		)
		(fp_line
			(start -0.12065 -0.2794)
			(end 0.12065 -0.2794)
			(stroke
				(width 0.1)
				(type default)
			)
			(layer "F.Fab")
		)
		(fp_line
			(start -0.12065 -0.305054)
			(end -0.12065 -0.2794)
			(stroke
				(width 0.1)
				(type default)
			)
			(layer "F.Fab")
		)
		(fp_line
			(start -0.67945 0.3048)
			(end -0.67945 -0.305054)
			(stroke
				(width 0.1)
				(type default)
			)
			(layer "F.Fab")
		)
		(fp_line
			(start -0.67945 -0.305054)
			(end -0.12065 -0.305054)
			(stroke
				(width 0.1)
				(type default)
			)
			(layer "F.Fab")
		)
		(pad "1" smd circle
			(at -0.40005 0 180)
			(size 0 0)
			(layers "F.Cu" "F.Mask" "F.Paste")
			(net "P3V3_AUX")
		)
		(pad "2" smd circle
			(at 0.40005 0 180)
			(size 0 0)
			(layers "F.Cu" "F.Mask" "F.Paste")
			(net "RST_SPI_PCH_FLASH_R1_N")
		)
	)
)
